# T6G (Grand Teton) — schematic netlist excerpt (pin names and nets, part order shuffled) for the footprints in the layout excerpt that follows; sources: Cadence DE-HDL packaged netlist, KiCad conversion of 04192023_DAF0TMB3IC0_F0TG_MB_C_brd_V02_OCP.brd

R268  Q_RES  0 5% CHIP  pkg 0402LF  page 82 : A = CPU1_SP5R3 ; B = FM_CPU1_SP5R3
C6664  Q_CAP_DIFFBUS  DIFF BUS_0.22UF 6.3V 20% X6S  pkg C0201  page 330 : \1\ = P5E_CPU1_P1_TX_BUF_C_DN<1> ; \2\ = P5E_CPU1_P1_TX_BUF_DN<1>
C2310  Q_CAP  22UF 4V 20% X6S  pkg C0402  page 73 : A = PVDDCR_CPU0_P1 ; B = GND

(kicad_pcb
	(version 20260206)
	(generator "pcbnew")
	(generator_version "10.0")
	(general
		(thickness 1.6)
		(legacy_teardrops no)
	)
	(paper "A4")
	(title_block
		(title "04192023_DAF0TMB3IC0_F0TG_MB_C_brd_V02_OCP.brd")
		(comment 1 "Grand Teton / footprints 6007-6009 of 8354")
	)
	(layers
		(0 "F.Cu" signal "TOP")
		(4 "In1.Cu" signal "GND")
		(6 "In2.Cu" signal "IN1")
		(8 "In3.Cu" signal "GND1")
		(10 "In4.Cu" signal "IN2")
		(12 "In5.Cu" signal "GND2")
		(14 "In6.Cu" signal "IN3")
		(16 "In7.Cu" signal "GND3")
		(18 "In8.Cu" signal "VCC")
		(20 "In9.Cu" signal "VCC1")
		(22 "In10.Cu" signal "GND4")
		(24 "In11.Cu" signal "IN4")
		(26 "In12.Cu" signal "GND5")
		(28 "In13.Cu" signal "IN5")
		(30 "In14.Cu" signal "GND6")
		(32 "In15.Cu" signal "IN6")
		(34 "In16.Cu" signal "GND7")
		(2 "B.Cu" signal "BOTTOM")
		(9 "F.Adhes" user "F.Adhesive")
		(11 "B.Adhes" user "B.Adhesive")
		(13 "F.Paste" user "Package Geometry/Pastemask Top")
		(15 "B.Paste" user "Package Geometry/Pastemask Bottom")
		(5 "F.SilkS" user "Ref Des/Silkscreen Top")
		(7 "B.SilkS" user "Ref Des/Silkscreen Bottom")
		(1 "F.Mask" user "Board Geometry/Soldermask Top")
		(3 "B.Mask" user "Board Geometry/Soldermask Bottom")
		(17 "Dwgs.User" user "User.Drawings")
		(19 "Cmts.User" user "User.Comments")
		(21 "Eco1.User" user "User.Eco1")
		(23 "Eco2.User" user "User.Eco2")
		(25 "Edge.Cuts" user "Board Geometry/Outline")
		(27 "Margin" user)
		(31 "F.CrtYd" user "Package Geometry/Place Bound Top")
		(29 "B.CrtYd" user "Package Geometry/Place Bound Bottom")
		(35 "F.Fab" user "Ref Des/Assembly Top")
		(33 "B.Fab" user "Ref Des/Assembly Bottom")
	)
	(footprint ""
		(layer "B.Cu")
		(at 98.51009 -248.479564 180)
		(property "Reference" "C2310"
			(at 0 0 0)
			(layer "B.SilkS")
			(hide yes)
			(effects
				(font
					(size 1.27 1.27)
				)
				(justify mirror)
			)
		)
		(property "Value" ""
			(at 0 0 0)
			(layer "B.Fab")
			(effects
				(font
					(size 1.27 1.27)
				)
				(justify mirror)
			)
		)
		(duplicate_pad_numbers_are_jumpers no)
		(fp_line
			(start 0.7874 0.4064)
			(end 0.7874 -0.4064)
			(stroke
				(width 0.1524)
				(type default)
			)
			(layer "B.SilkS")
		)
		(fp_line
			(start 0.7874 -0.4064)
			(end -0.7874 -0.4064)
			(stroke
				(width 0.1524)
				(type default)
			)
			(layer "B.SilkS")
		)
		(fp_line
			(start -0.7874 0.4064)
			(end 0.7874 0.4064)
			(stroke
				(width 0.1524)
				(type default)
			)
			(layer "B.SilkS")
		)
		(fp_line
			(start -0.7874 -0.4064)
			(end -0.7874 0.4064)
			(stroke
				(width 0.1524)
				(type default)
			)
			(layer "B.SilkS")
		)
		(fp_line
			(start 0.67945 0.3048)
			(end 0.67945 -0.305054)
			(stroke
				(width 0.1)
				(type default)
			)
			(layer "B.Fab")
		)
		(fp_line
			(start 0.67945 -0.305054)
			(end 0.12065 -0.305054)
			(stroke
				(width 0.1)
				(type default)
			)
			(layer "B.Fab")
		)
		(fp_line
			(start 0.12065 0.3048)
			(end 0.67945 0.3048)
			(stroke
				(width 0.1)
				(type default)
			)
			(layer "B.Fab")
		)
		(fp_line
			(start 0.12065 0.2794)
			(end 0.12065 0.3048)
			(stroke
				(width 0.1)
				(type default)
			)
			(layer "B.Fab")
		)
		(fp_line
			(start 0.12065 -0.2794)
			(end -0.12065 -0.2794)
			(stroke
				(width 0.1)
				(type default)
			)
			(layer "B.Fab")
		)
		(fp_line
			(start 0.12065 -0.305054)
			(end 0.12065 -0.2794)
			(stroke
				(width 0.1)
				(type default)
			)
			(layer "B.Fab")
		)
		(fp_line
			(start -0.120396 0.3048)
			(end -0.120396 0.2794)
			(stroke
				(width 0.1)
				(type default)
			)
			(layer "B.Fab")
		)
		(fp_line
			(start -0.120396 0.2794)
			(end 0.12065 0.2794)
			(stroke
				(width 0.1)
				(type default)
			)
			(layer "B.Fab")
		)
		(fp_line
			(start -0.12065 -0.2794)
			(end -0.12065 -0.3048)
			(stroke
				(width 0.1)
				(type default)
			)
			(layer "B.Fab")
		)
		(fp_line
			(start -0.12065 -0.3048)
			(end -0.67945 -0.3048)
			(stroke
				(width 0.1)
				(type default)
			)
			(layer "B.Fab")
		)
		(fp_line
			(start -0.67945 0.3048)
			(end -0.120396 0.3048)
			(stroke
				(width 0.1)
				(type default)
			)
			(layer "B.Fab")
		)
		(fp_line
			(start -0.67945 -0.3048)
			(end -0.67945 0.3048)
			(stroke
				(width 0.1)
				(type default)
			)
			(layer "B.Fab")
		)
		(pad "1" smd circle
			(at 0.40005 0)
			(size 0 0)
			(layers "B.Cu" "B.Mask" "B.Paste")
			(net "PVDDCR_CPU0_P1")
		)
		(pad "2" smd circle
			(at -0.40005 0)
			(size 0 0)
			(layers "B.Cu" "B.Mask" "B.Paste")
			(net "GND")
		)
	)
	(footprint ""
		(layer "B.Cu")
		(at 52.363624 -408.517344 90)
		(property "Reference" "C6664"
			(at 0 0 90)
			(layer "B.SilkS")
			(hide yes)
			(effects
				(font
					(size 1.27 1.27)
				)
				(justify mirror)
			)
		)
		(property "Value" ""
			(at 0 0 90)
			(layer "B.Fab")
			(effects
				(font
					(size 1.27 1.27)
				)
				(justify mirror)
			)
		)
		(duplicate_pad_numbers_are_jumpers no)
		(fp_line
			(start 0.299974 -0.150114)
			(end -0.299974 -0.150114)
			(stroke
				(width 0.1)
				(type default)
			)
			(layer "B.Fab")
		)
		(fp_line
			(start -0.299974 -0.150114)
			(end -0.299974 0.150114)
			(stroke
				(width 0.1)
				(type default)
			)
			(layer "B.Fab")
		)
		(fp_line
			(start 0.299974 0.150114)
			(end 0.299974 -0.150114)
			(stroke
				(width 0.1)
				(type default)
			)
			(layer "B.Fab")
		)
		(fp_line
			(start -0.299974 0.150114)
			(end 0.299974 0.150114)
			(stroke
				(width 0.1)
				(type default)
			)
			(layer "B.Fab")
		)
		(pad "1" smd rect
			(at 0.2667 0 270)
			(size 0.3048 0.381)
			(layers "B.Cu" "B.Mask" "B.Paste")
			(net "P5E_CPU1_P1_TX_BUF_C_DN<1>")
		)
		(pad "2" smd rect
			(at -0.2667 0 270)
			(size 0.3048 0.381)
			(layers "B.Cu" "B.Mask" "B.Paste")
			(net "P5E_CPU1_P1_TX_BUF_DN<1>")
		)
	)
	(footprint ""
		(layer "B.Cu")
		(at 191.897 -100.294948 -90)
		(property "Reference" "R268"
			(at 0 0 90)
			(layer "B.SilkS")
			(hide yes)
			(effects
				(font
					(size 1.27 1.27)
				)
				(justify mirror)
			)
		)
		(property "Value" ""
			(at 0 0 90)
			(layer "B.Fab")
			(effects
				(font
					(size 1.27 1.27)
				)
				(justify mirror)
			)
		)
		(duplicate_pad_numbers_are_jumpers no)
		(fp_line
			(start -0.7874 0.4064)
			(end 0.7874 0.4064)
			(stroke
				(width 0.1524)
				(type default)
			)
			(layer "B.SilkS")
		)
		(fp_line
			(start 0.7874 0.4064)
			(end 0.7874 -0.4064)
			(stroke
				(width 0.1524)
				(type default)
			)
			(layer "B.SilkS")
		)
		(fp_line
			(start -0.7874 -0.4064)
			(end -0.7874 0.4064)
			(stroke
				(width 0.1524)
				(type default)
			)
			(layer "B.SilkS")
		)
		(fp_line
			(start 0.7874 -0.4064)
			(end -0.7874 -0.4064)
			(stroke
				(width 0.1524)
				(type default)
			)
			(layer "B.SilkS")
		)
		(fp_line
			(start -0.67945 0.3048)
			(end -0.120396 0.3048)
			(stroke
				(width 0.1)
				(type default)
			)
			(layer "B.Fab")
		)
		(fp_line
			(start -0.120396 0.3048)
			(end -0.120396 0.2794)
			(stroke
				(width 0.1)
				(type default)
			)
			(layer "B.Fab")
		)
		(fp_line
			(start 0.12065 0.3048)
			(end 0.67945 0.3048)
			(stroke
				(width 0.1)
				(type default)
			)
			(layer "B.Fab")
		)
		(fp_line
			(start 0.67945 0.3048)
			(end 0.67945 -0.305054)
			(stroke
				(width 0.1)
				(type default)
			)
			(layer "B.Fab")
		)
		(fp_line
			(start -0.120396 0.2794)
			(end 0.12065 0.2794)
			(stroke
				(width 0.1)
				(type default)
			)
			(layer "B.Fab")
		)
		(fp_line
			(start 0.12065 0.2794)
			(end 0.12065 0.3048)
			(stroke
				(width 0.1)
				(type default)
			)
			(layer "B.Fab")
		)
		(fp_line
			(start -0.12065 -0.2794)
			(end -0.12065 -0.3048)
			(stroke
				(width 0.1)
				(type default)
			)
			(layer "B.Fab")
		)
		(fp_line
			(start 0.12065 -0.2794)
			(end -0.12065 -0.2794)
			(stroke
				(width 0.1)
				(type default)
			)
			(layer "B.Fab")
		)
		(fp_line
			(start -0.67945 -0.3048)
			(end -0.67945 0.3048)
			(stroke
				(width 0.1)
				(type default)
			)
			(layer "B.Fab")
		)
		(fp_line
			(start -0.12065 -0.3048)
			(end -0.67945 -0.3048)
			(stroke
				(width 0.1)
				(type default)
			)
			(layer "B.Fab")
		)
		(fp_line
			(start 0.12065 -0.305054)
			(end 0.12065 -0.2794)
			(stroke
				(width 0.1)
				(type default)
			)
			(layer "B.Fab")
		)
		(fp_line
			(start 0.67945 -0.305054)
			(end 0.12065 -0.305054)
			(stroke
				(width 0.1)
				(type default)
			)
			(layer "B.Fab")
		)
		(pad "1" smd circle
			(at 0.40005 0 90)
			(size 0 0)
			(layers "B.Cu" "B.Mask" "B.Paste")
			(net "CPU1_SP5R3")
		)
		(pad "2" smd circle
			(at -0.40005 0 90)
			(size 0 0)
			(layers "B.Cu" "B.Mask" "B.Paste")
			(net "FM_CPU1_SP5R3")
		)
	)
)
